(kicad_pcb
	(version 20241229)
	(generator "pcbnew")
	(generator_version "9.0")
	(general
		(thickness 1.61)
		(legacy_teardrops no)
	)
	(paper "A3")
	(title_block
		(title "RDIMM DDR5 Tester")
		(date "2026-05-21")
		(rev "2.2.0")
		(company "Antmicro")
		(comment 9 "footprints 157-160 of 796")
	)
	(layers
		(0 "F.Cu" signal)
		(4 "In1.Cu" power)
		(6 "In2.Cu" mixed)
		(8 "In3.Cu" power)
		(10 "In4.Cu" mixed)
		(12 "In5.Cu" power)
		(14 "In6.Cu" mixed)
		(16 "In7.Cu" power)
		(18 "In8.Cu" power)
		(20 "In9.Cu" mixed)
		(22 "In10.Cu" power)
		(2 "B.Cu" signal)
		(9 "F.Adhes" user "F.Adhesive")
		(11 "B.Adhes" user "B.Adhesive")
		(13 "F.Paste" user)
		(15 "B.Paste" user)
		(5 "F.SilkS" user "F.Silkscreen")
		(7 "B.SilkS" user "B.Silkscreen")
		(1 "F.Mask" user)
		(3 "B.Mask" user)
		(17 "Dwgs.User" user "User.Drawings")
		(19 "Cmts.User" user "User.Comments")
		(21 "Eco1.User" user "User.Eco1")
		(23 "Eco2.User" user "User.Eco2")
		(25 "Edge.Cuts" user)
		(27 "Margin" user)
		(31 "F.CrtYd" user "F.Courtyard")
		(29 "B.CrtYd" user "B.Courtyard")
		(35 "F.Fab" user)
		(33 "B.Fab" user)
	)
	(footprint "antmicro-footprints:DFN-10-1EP_3x3mm"
		(layer "F.Cu")
		(at 239.274499 170.2)
		(property "Reference" "U25"
			(at -1.049499 3.025 0)
			(layer "F.SilkS")
			(effects
				(font
					(size 0.7 0.7)
					(thickness 0.15)
				)
				(justify left bottom)
			)
		)
		(property "Value" "PAC1720-1"
			(at 0 2.8 0)
			(layer "F.Fab")
			(effects
				(font
					(size 0.7 0.7)
					(thickness 0.15)
				)
				(justify left bottom)
			)
		)
		(property "Datasheet" "https://ww1.microchip.com/downloads/aemDocuments/documents/MSLD/ProductDocuments/DataSheets/PAC1710-PAC1720-Data-Sheet-DS20005386.pdf"
			(at 0 0 0)
			(layer "F.Fab")
			(hide yes)
			(effects
				(font
					(size 1.27 1.27)
					(thickness 0.15)
				)
			)
		)
		(property "MPN" "PAC1720-1-AIA-TR"
			(at 0 0 0)
			(unlocked yes)
			(layer "F.Fab")
			(hide yes)
			(effects
				(font
					(size 1 1)
					(thickness 0.15)
				)
			)
		)
		(property "Manufacturer" "Microchip Technology"
			(at 0 0 0)
			(unlocked yes)
			(layer "F.Fab")
			(hide yes)
			(effects
				(font
					(size 1 1)
					(thickness 0.15)
				)
			)
		)
		(property "Author" "Antmicro"
			(at 0 0 0)
			(unlocked yes)
			(layer "F.Fab")
			(hide yes)
			(effects
				(font
					(size 1 1)
					(thickness 0.15)
				)
			)
		)
		(property "License" "Apache-2.0"
			(at 0 0 0)
			(unlocked yes)
			(layer "F.Fab")
			(hide yes)
			(effects
				(font
					(size 1 1)
					(thickness 0.15)
				)
			)
		)
		(property ki_fp_filters "UQFN*1EP*4x4mm*P0.65mm*")
		(sheetname "/Supply/DC-DC AUX, MGT/")
		(sheetfile "dc-dc-aux-mgt.kicad_sch")
		(attr smd)
		(fp_line
			(start -1.624 -1.226)
			(end -1.773 -1.226)
			(stroke
				(width 0.15)
				(type solid)
			)
			(layer "F.SilkS")
		)
		(fp_line
			(start -1.6 1.6)
			(end -1.6 1.35)
			(stroke
				(width 0.15)
				(type solid)
			)
			(layer "F.SilkS")
		)
		(fp_line
			(start -1.6 1.6)
			(end -1.35 1.6)
			(stroke
				(width 0.15)
				(type solid)
			)
			(layer "F.SilkS")
		)
		(fp_line
			(start -1.249 -1.601)
			(end -1.624 -1.226)
			(stroke
				(width 0.15)
				(type solid)
			)
			(layer "F.SilkS")
		)
		(fp_line
			(start -1.249 -1.601)
			(end -0.824 -1.601)
			(stroke
				(width 0.15)
				(type solid)
			)
			(layer "F.SilkS")
		)
		(fp_line
			(start 1.601 -1.601)
			(end 1.351 -1.601)
			(stroke
				(width 0.15)
				(type solid)
			)
			(layer "F.SilkS")
		)
		(fp_line
			(start 1.601 -1.601)
			(end 1.601 -1.401)
			(stroke
				(width 0.15)
				(type solid)
			)
			(layer "F.SilkS")
		)
		(fp_line
			(start 1.601 1.6)
			(end 1.401 1.6)
			(stroke
				(width 0.15)
				(type solid)
			)
			(layer "F.SilkS")
		)
		(fp_line
			(start 1.601 1.6)
			(end 1.601 1.35)
			(stroke
				(width 0.15)
				(type solid)
			)
			(layer "F.SilkS")
		)
		(fp_circle
			(center -1.8 -1.6)
			(end -1.8 -1.551)
			(stroke
				(width 0.15)
				(type solid)
			)
			(fill yes)
			(layer "F.SilkS")
		)
		(fp_line
			(start -1.91 -1.73)
			(end 1.89 -1.73)
			(stroke
				(width 0.05)
				(type solid)
			)
			(layer "F.CrtYd")
		)
		(fp_line
			(start -1.91 1.75)
			(end -1.91 -1.73)
			(stroke
				(width 0.05)
				(type solid)
			)
			(layer "F.CrtYd")
		)
		(fp_line
			(start 1.89 1.75)
			(end -1.91 1.75)
			(stroke
				(width 0.05)
				(type solid)
			)
			(layer "F.CrtYd")
		)
		(fp_line
			(start 1.89 1.75)
			(end 1.89 -1.73)
			(stroke
				(width 0.05)
				(type solid)
			)
			(layer "F.CrtYd")
		)
		(fp_line
			(start -1.499 -1.18)
			(end -1.179 -1.5)
			(stroke
				(width 0.15)
				(type solid)
			)
			(layer "F.Fab")
		)
		(fp_line
			(start -1.499 1.499)
			(end -1.499 -1.176)
			(stroke
				(width 0.15)
				(type solid)
			)
			(layer "F.Fab")
		)
		(fp_line
			(start 1.5 -1.5)
			(end -1.175 -1.5)
			(stroke
				(width 0.15)
				(type solid)
			)
			(layer "F.Fab")
		)
		(fp_line
			(start 1.5 -1.5)
			(end 1.5 1.499)
			(stroke
				(width 0.15)
				(type solid)
			)
			(layer "F.Fab")
		)
		(fp_line
			(start 1.5 1.499)
			(end -1.499 1.499)
			(stroke
				(width 0.15)
				(type solid)
			)
			(layer "F.Fab")
		)
		(fp_text user "Author: Antmicro"
			(at -1.75 7.2 0)
			(layer "F.Fab")
			(effects
				(font
					(size 0.7 0.7)
					(thickness 0.15)
				)
				(justify left bottom)
			)
		)
		(fp_text user "License: Apache-2.0"
			(at -1.75 8.4 0)
			(layer "F.Fab")
			(effects
				(font
					(size 0.7 0.7)
					(thickness 0.15)
				)
				(justify left bottom)
			)
		)
		(fp_text user "${REFERENCE}"
			(at -1.75 5.999 0)
			(layer "F.Fab")
			(effects
				(font
					(size 0.7 0.7)
					(thickness 0.15)
				)
				(justify left bottom)
			)
		)
		(pad "1" smd roundrect
			(at -1.425 -1 270)
			(size 0.25 0.7)
			(layers "F.Cu" "F.Mask" "F.Paste")
			(roundrect_rratio 0.25)
			(net 683 "/Supply/DC-DC AUX, MGT/MGTAVCC_SEN_+")
			(pinfunction "IN1+")
			(pintype "input")
		)
		(pad "2" smd roundrect
			(at -1.425 -0.5 270)
			(size 0.25 0.7)
			(layers "F.Cu" "F.Mask" "F.Paste")
			(roundrect_rratio 0.25)
			(net 691 "/Supply/DC-DC AUX, MGT/MGTAVCC_SEN_-")
			(pinfunction "IN1-")
			(pintype "input")
		)
		(pad "3" smd roundrect
			(at -1.425 0 270)
			(size 0.25 0.7)
			(layers "F.Cu" "F.Mask" "F.Paste")
			(roundrect_rratio 0.25)
			(net 682 "/Supply/DC-DC AUX, MGT/MGTAVTT_SEN_+")
			(pinfunction "IN2+")
			(pintype "input")
		)
		(pad "4" smd roundrect
			(at -1.425 0.498 270)
			(size 0.25 0.7)
			(layers "F.Cu" "F.Mask" "F.Paste")
			(roundrect_rratio 0.25)
			(net 690 "/Supply/DC-DC AUX, MGT/MGTAVTT_SEN_-")
			(pinfunction "IN2-")
			(pintype "input")
		)
		(pad "5" smd roundrect
			(at -1.425 0.998 270)
			(size 0.25 0.7)
			(layers "F.Cu" "F.Mask" "F.Paste")
			(roundrect_rratio 0.25)
			(net 1 "GND")
			(pinfunction "GND")
			(pintype "power_in")
		)
		(pad "6" smd roundrect
			(at 1.426 0.998 270)
			(size 0.25 0.7)
			(layers "F.Cu" "F.Mask" "F.Paste")
			(roundrect_rratio 0.25)
			(net 735 "Net-(U25-ADDRSEL)")
			(pinfunction "ADDRSEL")
			(pintype "bidirectional")
		)
		(pad "7" smd roundrect
			(at 1.426 0.498 270)
			(size 0.25 0.7)
			(layers "F.Cu" "F.Mask" "F.Paste")
			(roundrect_rratio 0.25)
			(net 731 "Net-(U25-~{ALERT})")
			(pinfunction "~{ALERT}")
			(pintype "bidirectional")
		)
		(pad "8" smd roundrect
			(at 1.426 0 270)
			(size 0.25 0.7)
			(layers "F.Cu" "F.Mask" "F.Paste")
			(roundrect_rratio 0.25)
			(net 533 "/I^{2}C + I3C/PWR.SDA")
			(pinfunction "SDA")
			(pintype "bidirectional")
		)
		(pad "9" smd roundrect
			(at 1.426 -0.5 270)
			(size 0.25 0.7)
			(layers "F.Cu" "F.Mask" "F.Paste")
			(roundrect_rratio 0.25)
			(net 749 "/I^{2}C + I3C/PWR.SCL")
			(pinfunction "SCL")
			(pintype "input")
		)
		(pad "10" smd roundrect
			(at 1.426 -1 270)
			(size 0.25 0.7)
			(layers "F.Cu" "F.Mask" "F.Paste")
			(roundrect_rratio 0.25)
			(net 38 "+3V3_AON")
			(pinfunction "VDD")
			(pintype "power_in")
		)
		(pad "11" smd roundrect
			(at 0 0 270)
			(size 2.38 1.65)
			(layers "F.Cu" "F.Mask" "F.Paste")
			(roundrect_rratio 0.05)
			(net 1 "GND")
			(pinfunction "EP")
			(pintype "passive")
		)
	)
	(footprint "antmicro-footprints:R_0402_1005Metric"
		(layer "F.Cu")
		(at 252.785 143.45 180)
		(descr "Resistor SMD 0402")
		(tags "resistor SMD 0402")
		(property "Reference" "R63"
			(at -3.065 -0.5 0)
			(layer "F.SilkS")
			(effects
				(font
					(size 0.7 0.7)
					(thickness 0.15)
				)
				(justify right bottom)
			)
		)
		(property "Value" "R_330R_0402"
			(at -1.011843 1.772047 0)
			(layer "F.Fab")
			(effects
				(font
					(size 0.7 0.7)
					(thickness 0.15)
				)
				(justify right bottom)
			)
		)
		(property "Datasheet" "https://www.bourns.com/docs/product-datasheets/cr.pdf"
			(at 0 0 180)
			(layer "F.Fab")
			(hide yes)
			(effects
				(font
					(size 1.27 1.27)
					(thickness 0.15)
				)
			)
		)
		(property "Manufacturer" "Bourns"
			(at 0 0 180)
			(unlocked yes)
			(layer "F.Fab")
			(hide yes)
			(effects
				(font
					(size 1 1)
					(thickness 0.15)
				)
			)
		)
		(property "MPN" "CR0402-FX-3300GLF"
			(at 0 0 180)
			(unlocked yes)
			(layer "F.Fab")
			(hide yes)
			(effects
				(font
					(size 1 1)
					(thickness 0.15)
				)
			)
		)
		(property "Val" "330R"
			(at 0 0 180)
			(unlocked yes)
			(layer "F.Fab")
			(hide yes)
			(effects
				(font
					(size 1 1)
					(thickness 0.15)
				)
			)
		)
		(property "License" "Apache-2.0"
			(at 0 0 180)
			(unlocked yes)
			(layer "F.Fab")
			(hide yes)
			(effects
				(font
					(size 1 1)
					(thickness 0.15)
				)
			)
		)
		(property "Author" "Antmicro"
			(at 0 0 180)
			(unlocked yes)
			(layer "F.Fab")
			(hide yes)
			(effects
				(font
					(size 1 1)
					(thickness 0.15)
				)
			)
		)
		(property "Tolerance" "1%"
			(at 0 0 180)
			(unlocked yes)
			(layer "F.Fab")
			(hide yes)
			(effects
				(font
					(size 1 1)
					(thickness 0.15)
				)
			)
		)
		(sheetname "/DDR5 RDIMM/")
		(sheetfile "ddr5-rdimm.kicad_sch")
		(attr smd)
		(fp_rect
			(start -0.925 -0.47)
			(end 0.925 0.47)
			(stroke
				(width 0.05)
				(type default)
			)
			(fill no)
			(layer "F.CrtYd")
		)
		(fp_rect
			(start -0.5 -0.25)
			(end 0.5 0.25)
			(stroke
				(width 0.15)
				(type solid)
			)
			(fill no)
			(layer "F.Fab")
		)
		(fp_text user "License: Apache-2.0"
			(at -0.95 5.169 180)
			(layer "F.Fab")
			(effects
				(font
					(size 0.7 0.7)
					(thickness 0.15)
				)
				(justify left bottom)
			)
		)
		(fp_text user "${REFERENCE}"
			(at -0.95 3.168 180)
			(layer "F.Fab")
			(effects
				(font
					(size 0.7 0.7)
					(thickness 0.15)
				)
				(justify left bottom)
			)
		)
		(fp_text user "Author: Antmicro"
			(at -0.95 4.169 180)
			(layer "F.Fab")
			(effects
				(font
					(size 0.7 0.7)
					(thickness 0.15)
				)
				(justify left bottom)
			)
		)
		(pad "1" smd roundrect
			(at -0.48 0 180)
			(size 0.59 0.64)
			(layers "F.Cu" "F.Mask" "F.Paste")
			(roundrect_rratio 0.25)
			(net 221 "Net-(D20-C_{R})")
			(pintype "passive")
		)
		(pad "2" smd roundrect
			(at 0.48 0 180)
			(size 0.59 0.64)
			(layers "F.Cu" "F.Mask" "F.Paste")
			(roundrect_rratio 0.25)
			(net 283 "Net-(Q11-D)")
			(pintype "passive")
		)
	)
	(footprint "antmicro-footprints:TP_SMD_1mm"
		(layer "F.Cu")
		(at 244.024499 179.299)
		(property "Reference" "TP18"
			(at 0 -0.731898 0)
			(layer "F.SilkS")
			(hide yes)
			(effects
				(font
					(size 0.7 0.7)
					(thickness 0.15)
				)
				(justify left bottom)
			)
		)
		(property "Value" "TP_1mm_SMD"
			(at 0 1.4 0)
			(layer "F.Fab")
			(effects
				(font
					(size 0.7 0.7)
					(thickness 0.15)
				)
				(justify left bottom)
			)
		)
		(property "MPN" ""
			(at 0 0 0)
			(unlocked yes)
			(layer "F.Fab")
			(hide yes)
			(effects
				(font
					(size 1 1)
					(thickness 0.15)
				)
			)
		)
		(property "Manufacturer" ""
			(at 0 0 0)
			(unlocked yes)
			(layer "F.Fab")
			(hide yes)
			(effects
				(font
					(size 1 1)
					(thickness 0.15)
				)
			)
		)
		(property "Author" "Antmicro"
			(at 0 0 0)
			(unlocked yes)
			(layer "F.Fab")
			(hide yes)
			(effects
				(font
					(size 1 1)
					(thickness 0.15)
				)
			)
		)
		(property "License" "Apache-2.0"
			(at 0 0 0)
			(unlocked yes)
			(layer "F.Fab")
			(hide yes)
			(effects
				(font
					(size 1 1)
					(thickness 0.15)
				)
			)
		)
		(sheetname "/Supply/DC-DC AUX, MGT/")
		(sheetfile "dc-dc-aux-mgt.kicad_sch")
		(attr exclude_from_pos_files)
		(fp_circle
			(center 0 0)
			(end 0.6 0)
			(stroke
				(width 0.05)
				(type default)
			)
			(fill no)
			(layer "F.CrtYd")
		)
		(fp_text user "Author: Antmicro"
			(at -0.5 4 0)
			(layer "F.Fab")
			(effects
				(font
					(size 0.7 0.7)
					(thickness 0.15)
				)
				(justify left bottom)
			)
		)
		(fp_text user "License: Apache-2.0"
			(at -0.5 5.2 0)
			(layer "F.Fab")
			(effects
				(font
					(size 0.7 0.7)
					(thickness 0.15)
				)
				(justify left bottom)
			)
		)
		(fp_text user "${REFERENCE}"
			(at -0.5 2.8 0)
			(layer "F.Fab")
			(effects
				(font
					(size 0.7 0.7)
					(thickness 0.15)
				)
				(justify left bottom)
			)
		)
		(pad "1" smd circle
			(at 0 0)
			(size 1 1)
			(layers "F.Cu" "F.Mask")
			(net 573 "+1V8_MGTVCCAUX")
			(pinfunction "1")
			(pintype "passive")
		)
	)
	(footprint "antmicro-footprints:C_0805_2012Metric"
		(layer "F.Cu")
		(at 230.010001 187.669999)
		(descr "Capacitor SMD 0805")
		(tags "capacitor SMD 0805")
		(property "Reference" "C314"
			(at 1.915 0.45 0)
			(layer "F.SilkS")
			(effects
				(font
					(size 0.7 0.7)
					(thickness 0.15)
				)
				(justify left bottom)
			)
		)
		(property "Value" "C_22u_25V_0805"
			(at -2.055717 1.963152 0)
			(layer "F.Fab")
			(effects
				(font
					(size 0.7 0.7)
					(thickness 0.15)
				)
				(justify left bottom)
			)
		)
		(property "Datasheet" "https://product.samsungsem.com/mlcc/CL21A226MAYNNN.do"
			(at 0 0 0)
			(layer "F.Fab")
			(hide yes)
			(effects
				(font
					(size 1.27 1.27)
					(thickness 0.15)
				)
			)
		)
		(property "MPN" "CL21A226MAYNNNE"
			(at 0 0 0)
			(unlocked yes)
			(layer "F.Fab")
			(hide yes)
			(effects
				(font
					(size 1 1)
					(thickness 0.15)
				)
			)
		)
		(property "Manufacturer" "Samsung Electro-Mechanics"
			(at 0 0 0)
			(unlocked yes)
			(layer "F.Fab")
			(hide yes)
			(effects
				(font
					(size 1 1)
					(thickness 0.15)
				)
			)
		)
		(property "License" "Apache-2.0"
			(at 0 0 0)
			(unlocked yes)
			(layer "F.Fab")
			(hide yes)
			(effects
				(font
					(size 1 1)
					(thickness 0.15)
				)
			)
		)
		(property "Author" "Antmicro"
			(at 0 0 0)
			(unlocked yes)
			(layer "F.Fab")
			(hide yes)
			(effects
				(font
					(size 1 1)
					(thickness 0.15)
				)
			)
		)
		(property "Val" "22u"
			(at 0 0 0)
			(unlocked yes)
			(layer "F.Fab")
			(hide yes)
			(effects
				(font
					(size 1 1)
					(thickness 0.15)
				)
			)
		)
		(property "Voltage" "25V"
			(at 0 0 0)
			(unlocked yes)
			(layer "F.Fab")
			(hide yes)
			(effects
				(font
					(size 1 1)
					(thickness 0.15)
				)
			)
		)
		(property "Dielectric" "X5R"
			(at 0 0 0)
			(unlocked yes)
			(layer "F.Fab")
			(hide yes)
			(effects
				(font
					(size 1 1)
					(thickness 0.15)
				)
			)
		)
		(property "Public" "False"
			(at 0 0 0)
			(unlocked yes)
			(layer "F.Fab")
			(hide yes)
			(effects
				(font
					(size 1 1)
					(thickness 0.15)
				)
			)
		)
		(sheetname "/Supply/DC-DC VCCINT/")
		(sheetfile "dc-dc-vccint.kicad_sch")
		(attr smd exclude_from_bom)
		(fp_line
			(start -0.3 -0.7)
			(end 0.3 -0.7)
			(stroke
				(width 0.15)
				(type solid)
			)
			(layer "F.SilkS")
		)
		(fp_line
			(start -0.3 0.7)
			(end 0.3 0.7)
			(stroke
				(width 0.15)
				(type solid)
			)
			(layer "F.SilkS")
		)
		(fp_rect
			(start 1.95 -0.9)
			(end -1.95 0.9)
			(stroke
				(width 0.05)
				(type default)
			)
			(fill no)
			(layer "F.CrtYd")
		)
		(fp_rect
			(start -0.95 -0.675)
			(end 0.95 0.675)
			(stroke
				(width 0.15)
				(type solid)
			)
			(fill no)
			(layer "F.Fab")
		)
		(fp_text user "${REFERENCE}"
			(at -1.9 3.947 0)
			(layer "F.Fab")
			(effects
				(font
					(size 0.7 0.7)
					(thickness 0.15)
				)
				(justify left bottom)
			)
		)
		(fp_text user "License: Apache-2.0"
			(at -1.9 4.947 0)
			(layer "F.Fab")
			(effects
				(font
					(size 0.7 0.7)
					(thickness 0.15)
				)
				(justify left bottom)
			)
		)
		(fp_text user "Author: Antmicro"
			(at -1.9 5.947 0)
			(layer "F.Fab")
			(effects
				(font
					(size 0.7 0.7)
					(thickness 0.15)
				)
				(justify left bottom)
			)
		)
		(pad "1" smd roundrect
			(at -1.1 0)
			(size 1.2 1.3)
			(layers "F.Cu" "F.Mask" "F.Paste")
			(roundrect_rratio 0.25)
			(net 1 "GND")
			(pintype "passive")
		)
		(pad "2" smd roundrect
			(at 1.1 0)
			(size 1.2 1.3)
			(layers "F.Cu" "F.Mask" "F.Paste")
			(roundrect_rratio 0.25)
			(net 35 "VDC")
			(pintype "passive")
		)
	)
)
